# T6G (Grand Teton) — schematic netlist excerpt (pin names and nets, part order shuffled) for the footprints in the layout excerpt that follows; sources: Cadence DE-HDL packaged netlist, KiCad conversion of 04192023_DAF0TMB3IC0_F0TG_MB_C_brd_V02_OCP.brd

C590  Q_CAP  22UF 4V 20% X6S  pkg C0402  page 290 : A = P1V8_CPU0_RT1_1A ; B = GND
C1518  Q_CAP  0.1UF 16V 10% X7R  pkg C0402  page 173 : A = PVDD18_S5_P0 ; B = GND

(kicad_pcb
	(version 20260206)
	(generator "pcbnew")
	(generator_version "10.0")
	(general
		(thickness 1.6)
		(legacy_teardrops no)
	)
	(paper "A4")
	(title_block
		(title "04192023_DAF0TMB3IC0_F0TG_MB_C_brd_V02_OCP.brd")
		(comment 1 "Grand Teton / footprints 2957-2958 of 8354")
	)
	(layers
		(0 "F.Cu" signal "TOP")
		(4 "In1.Cu" signal "GND")
		(6 "In2.Cu" signal "IN1")
		(8 "In3.Cu" signal "GND1")
		(10 "In4.Cu" signal "IN2")
		(12 "In5.Cu" signal "GND2")
		(14 "In6.Cu" signal "IN3")
		(16 "In7.Cu" signal "GND3")
		(18 "In8.Cu" signal "VCC")
		(20 "In9.Cu" signal "VCC1")
		(22 "In10.Cu" signal "GND4")
		(24 "In11.Cu" signal "IN4")
		(26 "In12.Cu" signal "GND5")
		(28 "In13.Cu" signal "IN5")
		(30 "In14.Cu" signal "GND6")
		(32 "In15.Cu" signal "IN6")
		(34 "In16.Cu" signal "GND7")
		(2 "B.Cu" signal "BOTTOM")
		(9 "F.Adhes" user "F.Adhesive")
		(11 "B.Adhes" user "B.Adhesive")
		(13 "F.Paste" user "Package Geometry/Pastemask Top")
		(15 "B.Paste" user "Package Geometry/Pastemask Bottom")
		(5 "F.SilkS" user "Ref Des/Silkscreen Top")
		(7 "B.SilkS" user "Ref Des/Silkscreen Bottom")
		(1 "F.Mask" user "Board Geometry/Soldermask Top")
		(3 "B.Mask" user "Board Geometry/Soldermask Bottom")
		(17 "Dwgs.User" user "User.Drawings")
		(19 "Cmts.User" user "User.Comments")
		(21 "Eco1.User" user "User.Eco1")
		(23 "Eco2.User" user "User.Eco2")
		(25 "Edge.Cuts" user "Board Geometry/Outline")
		(27 "Margin" user)
		(31 "F.CrtYd" user "Package Geometry/Place Bound Top")
		(29 "B.CrtYd" user "Package Geometry/Place Bound Bottom")
		(35 "F.Fab" user "Ref Des/Assembly Top")
		(33 "B.Fab" user "Ref Des/Assembly Bottom")
	)
	(footprint ""
		(layer "F.Cu")
		(at 127.705104 -54.17439 180)
		(property "Reference" "C1518"
			(at 0 0 180)
			(layer "F.SilkS")
			(hide yes)
			(effects
				(font
					(size 1.27 1.27)
				)
			)
		)
		(property "Value" ""
			(at 0 0 180)
			(layer "F.Fab")
			(effects
				(font
					(size 1.27 1.27)
				)
			)
		)
		(duplicate_pad_numbers_are_jumpers no)
		(fp_line
			(start 0.7874 0.4064)
			(end -0.7874 0.4064)
			(stroke
				(width 0.1524)
				(type default)
			)
			(layer "F.SilkS")
		)
		(fp_line
			(start 0.7874 -0.4064)
			(end 0.7874 0.4064)
			(stroke
				(width 0.1524)
				(type default)
			)
			(layer "F.SilkS")
		)
		(fp_line
			(start -0.7874 0.4064)
			(end -0.7874 -0.4064)
			(stroke
				(width 0.1524)
				(type default)
			)
			(layer "F.SilkS")
		)
		(fp_line
			(start -0.7874 -0.4064)
			(end 0.7874 -0.4064)
			(stroke
				(width 0.1524)
				(type default)
			)
			(layer "F.SilkS")
		)
		(fp_line
			(start 0.67945 0.3048)
			(end 0.120396 0.3048)
			(stroke
				(width 0.1)
				(type default)
			)
			(layer "F.Fab")
		)
		(fp_line
			(start 0.67945 -0.3048)
			(end 0.67945 0.3048)
			(stroke
				(width 0.1)
				(type default)
			)
			(layer "F.Fab")
		)
		(fp_line
			(start 0.12065 -0.2794)
			(end 0.12065 -0.3048)
			(stroke
				(width 0.1)
				(type default)
			)
			(layer "F.Fab")
		)
		(fp_line
			(start 0.12065 -0.3048)
			(end 0.67945 -0.3048)
			(stroke
				(width 0.1)
				(type default)
			)
			(layer "F.Fab")
		)
		(fp_line
			(start 0.120396 0.3048)
			(end 0.120396 0.2794)
			(stroke
				(width 0.1)
				(type default)
			)
			(layer "F.Fab")
		)
		(fp_line
			(start 0.120396 0.2794)
			(end -0.12065 0.2794)
			(stroke
				(width 0.1)
				(type default)
			)
			(layer "F.Fab")
		)
		(fp_line
			(start -0.12065 0.3048)
			(end -0.67945 0.3048)
			(stroke
				(width 0.1)
				(type default)
			)
			(layer "F.Fab")
		)
		(fp_line
			(start -0.12065 0.2794)
			(end -0.12065 0.3048)
			(stroke
				(width 0.1)
				(type default)
			)
			(layer "F.Fab")
		)
		(fp_line
			(start -0.12065 -0.2794)
			(end 0.12065 -0.2794)
			(stroke
				(width 0.1)
				(type default)
			)
			(layer "F.Fab")
		)
		(fp_line
			(start -0.12065 -0.305054)
			(end -0.12065 -0.2794)
			(stroke
				(width 0.1)
				(type default)
			)
			(layer "F.Fab")
		)
		(fp_line
			(start -0.67945 0.3048)
			(end -0.67945 -0.305054)
			(stroke
				(width 0.1)
				(type default)
			)
			(layer "F.Fab")
		)
		(fp_line
			(start -0.67945 -0.305054)
			(end -0.12065 -0.305054)
			(stroke
				(width 0.1)
				(type default)
			)
			(layer "F.Fab")
		)
		(pad "1" smd circle
			(at -0.40005 0 180)
			(size 0 0)
			(layers "F.Cu" "F.Mask" "F.Paste")
			(net "PVDD18_S5_P0")
		)
		(pad "2" smd circle
			(at 0.40005 0 180)
			(size 0 0)
			(layers "F.Cu" "F.Mask" "F.Paste")
			(net "GND")
		)
	)
	(footprint ""
		(layer "F.Cu")
		(at 358.021128 -394.82268 90)
		(property "Reference" "C590"
			(at 0 0 90)
			(layer "F.SilkS")
			(hide yes)
			(effects
				(font
					(size 1.27 1.27)
				)
			)
		)
		(property "Value" ""
			(at 0 0 90)
			(layer "F.Fab")
			(effects
				(font
					(size 1.27 1.27)
				)
			)
		)
		(duplicate_pad_numbers_are_jumpers no)
		(fp_line
			(start 0.7874 -0.4064)
			(end 0.7874 0.4064)
			(stroke
				(width 0.1524)
				(type default)
			)
			(layer "F.SilkS")
		)
		(fp_line
			(start -0.7874 -0.4064)
			(end 0.7874 -0.4064)
			(stroke
				(width 0.1524)
				(type default)
			)
			(layer "F.SilkS")
		)
		(fp_line
			(start 0.7874 0.4064)
			(end -0.7874 0.4064)
			(stroke
				(width 0.1524)
				(type default)
			)
			(layer "F.SilkS")
		)
		(fp_line
			(start -0.7874 0.4064)
			(end -0.7874 -0.4064)
			(stroke
				(width 0.1524)
				(type default)
			)
			(layer "F.SilkS")
		)
		(fp_line
			(start -0.12065 -0.305054)
			(end -0.12065 -0.2794)
			(stroke
				(width 0.1)
				(type default)
			)
			(layer "F.Fab")
		)
		(fp_line
			(start -0.67945 -0.305054)
			(end -0.12065 -0.305054)
			(stroke
				(width 0.1)
				(type default)
			)
			(layer "F.Fab")
		)
		(fp_line
			(start 0.67945 -0.3048)
			(end 0.67945 0.3048)
			(stroke
				(width 0.1)
				(type default)
			)
			(layer "F.Fab")
		)
		(fp_line
			(start 0.12065 -0.3048)
			(end 0.67945 -0.3048)
			(stroke
				(width 0.1)
				(type default)
			)
			(layer "F.Fab")
		)
		(fp_line
			(start 0.12065 -0.2794)
			(end 0.12065 -0.3048)
			(stroke
				(width 0.1)
				(type default)
			)
			(layer "F.Fab")
		)
		(fp_line
			(start -0.12065 -0.2794)
			(end 0.12065 -0.2794)
			(stroke
				(width 0.1)
				(type default)
			)
			(layer "F.Fab")
		)
		(fp_line
			(start 0.120396 0.2794)
			(end -0.12065 0.2794)
			(stroke
				(width 0.1)
				(type default)
			)
			(layer "F.Fab")
		)
		(fp_line
			(start -0.12065 0.2794)
			(end -0.12065 0.3048)
			(stroke
				(width 0.1)
				(type default)
			)
			(layer "F.Fab")
		)
		(fp_line
			(start 0.67945 0.3048)
			(end 0.120396 0.3048)
			(stroke
				(width 0.1)
				(type default)
			)
			(layer "F.Fab")
		)
		(fp_line
			(start 0.120396 0.3048)
			(end 0.120396 0.2794)
			(stroke
				(width 0.1)
				(type default)
			)
			(layer "F.Fab")
		)
		(fp_line
			(start -0.12065 0.3048)
			(end -0.67945 0.3048)
			(stroke
				(width 0.1)
				(type default)
			)
			(layer "F.Fab")
		)
		(fp_line
			(start -0.67945 0.3048)
			(end -0.67945 -0.305054)
			(stroke
				(width 0.1)
				(type default)
			)
			(layer "F.Fab")
		)
		(pad "1" smd circle
			(at -0.40005 0 90)
			(size 0 0)
			(layers "F.Cu" "F.Mask" "F.Paste")
			(net "P1V8_CPU0_RT1_1A")
		)
		(pad "2" smd circle
			(at 0.40005 0 90)
			(size 0 0)
			(layers "F.Cu" "F.Mask" "F.Paste")
			(net "GND")
		)
	)
)
